(kicad_pcb
	(version 20241229)
	(generator "pcbnew")
	(generator_version "9.0")
	(general
		(thickness 1.6296)
		(legacy_teardrops no)
	)
	(paper "A3")
	(title_block
		(title "Thunderbolt to 10GbE adapter")
		(date "2026-04-21")
		(rev "1.1.0")
		(company "Antmicro Ltd")
		(comment 1 "www.antmicro.com")
		(comment 9 "footprints 151-154 of 703")
	)
	(layers
		(0 "F.Cu" signal)
		(4 "In1.Cu" signal)
		(6 "In2.Cu" signal)
		(8 "In3.Cu" signal)
		(10 "In4.Cu" signal)
		(12 "In5.Cu" signal)
		(14 "In6.Cu" signal)
		(2 "B.Cu" signal)
		(9 "F.Adhes" user "F.Adhesive")
		(11 "B.Adhes" user "B.Adhesive")
		(13 "F.Paste" user)
		(15 "B.Paste" user)
		(5 "F.SilkS" user "F.Silkscreen")
		(7 "B.SilkS" user "B.Silkscreen")
		(1 "F.Mask" user)
		(3 "B.Mask" user)
		(17 "Dwgs.User" user "User.Drawings")
		(19 "Cmts.User" user "User.Comments")
		(21 "Eco1.User" user "User.Eco1")
		(23 "Eco2.User" user "User.Eco2")
		(25 "Edge.Cuts" user)
		(27 "Margin" user)
		(31 "F.CrtYd" user "F.Courtyard")
		(29 "B.CrtYd" user "B.Courtyard")
		(35 "F.Fab" user)
		(33 "B.Fab" user)
	)
	(footprint "antmicro-footprints:C_0805_2012Metric"
		(layer "F.Cu")
		(at 152.95 56.8 -90)
		(descr "Capacitor SMD 0805")
		(tags "capacitor SMD 0805")
		(property "Reference" "C321"
			(at 4.6 -0.65 270)
			(layer "F.SilkS")
			(effects
				(font
					(size 0.7 0.7)
					(thickness 0.15)
				)
				(justify left bottom)
			)
		)
		(property "Value" "C_22u_25V_0805"
			(at -2.055717 1.963152 270)
			(layer "F.Fab")
			(effects
				(font
					(size 0.7 0.7)
					(thickness 0.15)
				)
				(justify left bottom)
			)
		)
		(property "Datasheet" "https://product.samsungsem.com/mlcc/CL21A226MAYNNN.do"
			(at 0 0 270)
			(layer "F.Fab")
			(hide yes)
			(effects
				(font
					(size 1.27 1.27)
					(thickness 0.15)
				)
			)
		)
		(property "Description" "SMT Multilayer Ceramic Capacitor, 22uF, +/-20%, 25V, X5R, 0805 [2012 Metric]"
			(at 0 0 270)
			(layer "F.Fab")
			(hide yes)
			(effects
				(font
					(size 1.27 1.27)
					(thickness 0.15)
				)
			)
		)
		(property "MPN" "CL21A226MAYNNNE"
			(at 0 0 270)
			(unlocked yes)
			(layer "F.Fab")
			(hide yes)
			(effects
				(font
					(size 1 1)
					(thickness 0.15)
				)
			)
		)
		(property "Manufacturer" "Samsung Electro-Mechanics"
			(at 0 0 270)
			(unlocked yes)
			(layer "F.Fab")
			(hide yes)
			(effects
				(font
					(size 1 1)
					(thickness 0.15)
				)
			)
		)
		(property "License" "Apache-2.0"
			(at 0 0 270)
			(unlocked yes)
			(layer "F.Fab")
			(hide yes)
			(effects
				(font
					(size 1 1)
					(thickness 0.15)
				)
			)
		)
		(property "Author" "Antmicro"
			(at 0 0 270)
			(unlocked yes)
			(layer "F.Fab")
			(hide yes)
			(effects
				(font
					(size 1 1)
					(thickness 0.15)
				)
			)
		)
		(property "Val" "22u"
			(at 0 0 270)
			(unlocked yes)
			(layer "F.Fab")
			(hide yes)
			(effects
				(font
					(size 1 1)
					(thickness 0.15)
				)
			)
		)
		(property "Voltage" "25V"
			(at 0 0 270)
			(unlocked yes)
			(layer "F.Fab")
			(hide yes)
			(effects
				(font
					(size 1 1)
					(thickness 0.15)
				)
			)
		)
		(property "Dielectric" "X5R"
			(at 0 0 270)
			(unlocked yes)
			(layer "F.Fab")
			(hide yes)
			(effects
				(font
					(size 1 1)
					(thickness 0.15)
				)
			)
		)
		(property "Public" "False"
			(at 0 0 270)
			(unlocked yes)
			(layer "F.Fab")
			(hide yes)
			(effects
				(font
					(size 1 1)
					(thickness 0.15)
				)
			)
		)
		(sheetname "/Power input/")
		(sheetfile "power_input.kicad_sch")
		(attr smd)
		(fp_line
			(start -0.3 0.7)
			(end 0.3 0.7)
			(stroke
				(width 0.15)
				(type solid)
			)
			(layer "F.SilkS")
		)
		(fp_line
			(start -0.3 -0.7)
			(end 0.3 -0.7)
			(stroke
				(width 0.15)
				(type solid)
			)
			(layer "F.SilkS")
		)
		(fp_rect
			(start 1.95 -0.9)
			(end -1.95 0.9)
			(stroke
				(width 0.05)
				(type default)
			)
			(fill no)
			(layer "F.CrtYd")
		)
		(fp_rect
			(start -0.95 -0.675)
			(end 0.95 0.675)
			(stroke
				(width 0.15)
				(type solid)
			)
			(fill no)
			(layer "F.Fab")
		)
		(fp_text user "${REFERENCE}"
			(at -1.9 3.947 270)
			(layer "F.Fab")
			(effects
				(font
					(size 0.7 0.7)
					(thickness 0.15)
				)
				(justify left bottom)
			)
		)
		(fp_text user "License: Apache-2.0"
			(at -1.9 4.947 270)
			(layer "F.Fab")
			(effects
				(font
					(size 0.7 0.7)
					(thickness 0.15)
				)
				(justify left bottom)
			)
		)
		(fp_text user "Author: Antmicro"
			(at -1.9 5.947 270)
			(layer "F.Fab")
			(effects
				(font
					(size 0.7 0.7)
					(thickness 0.15)
				)
				(justify left bottom)
			)
		)
		(pad "1" smd roundrect
			(at -1.1 0 270)
			(size 1.2 1.3)
			(layers "F.Cu" "F.Mask" "F.Paste")
			(roundrect_rratio 0.25)
			(net 23 "GND")
			(pintype "passive")
		)
		(pad "2" smd roundrect
			(at 1.1 0 270)
			(size 1.2 1.3)
			(layers "F.Cu" "F.Mask" "F.Paste")
			(roundrect_rratio 0.25)
			(net 349 "/Power input/5V_OUT")
			(pintype "passive")
		)
	)
	(footprint "antmicro-footprints:L_Bourns-SRP4021HMT"
		(layer "F.Cu")
		(at 154.850001 106.000001 -90)
		(property "Reference" "L6"
			(at 17.549996 -13.650003 270)
			(layer "F.SilkS")
			(effects
				(font
					(size 0.7 0.7)
					(thickness 0.15)
				)
			)
		)
		(property "Value" "L_1u_10A_Bourns-SRP4021HMT"
			(at -2.85 3.4 270)
			(layer "F.Fab")
			(effects
				(font
					(size 0.7 0.7)
					(thickness 0.15)
				)
				(justify left bottom)
			)
		)
		(property "Datasheet" "https://www.mouser.com/datasheet/2/54/Bourns_04_01_2025_SRP4021HMT_Datasheet-3580094.pdf"
			(at 0 0 270)
			(layer "F.Fab")
			(effects
				(font
					(size 0.7 0.7)
					(thickness 0.15)
				)
				(justify left bottom)
			)
		)
		(property "Description" "Power Inductors - SMD Ind,4.1x4.2x1.9mm,1uH+/-20%,10A, Shielded"
			(at 0 0 270)
			(layer "F.Fab")
			(effects
				(font
					(size 0.7 0.7)
					(thickness 0.15)
				)
				(justify left bottom)
			)
		)
		(property "Val" "1u/10A"
			(at 0 0 270)
			(unlocked yes)
			(layer "F.Fab")
			(hide yes)
			(effects
				(font
					(size 1 1)
					(thickness 0.15)
				)
			)
		)
		(property "Manufacturer" "Bourns"
			(at 0 0 270)
			(unlocked yes)
			(layer "F.Fab")
			(hide yes)
			(effects
				(font
					(size 1 1)
					(thickness 0.15)
				)
			)
		)
		(property "MPN" "SRP4021HMT-1R0M"
			(at 0 0 270)
			(unlocked yes)
			(layer "F.Fab")
			(hide yes)
			(effects
				(font
					(size 1 1)
					(thickness 0.15)
				)
			)
		)
		(property "ISat" ""
			(at 0 0 270)
			(unlocked yes)
			(layer "F.Fab")
			(hide yes)
			(effects
				(font
					(size 1 1)
					(thickness 0.15)
				)
			)
		)
		(property "Isat" "8A"
			(at 0 0 270)
			(unlocked yes)
			(layer "F.Fab")
			(hide yes)
			(effects
				(font
					(size 1 1)
					(thickness 0.15)
				)
			)
		)
		(property "IMax" ""
			(at 0 0 270)
			(unlocked yes)
			(layer "F.Fab")
			(hide yes)
			(effects
				(font
					(size 1 1)
					(thickness 0.15)
				)
			)
		)
		(property "Imax" "10A"
			(at 0 0 270)
			(unlocked yes)
			(layer "F.Fab")
			(hide yes)
			(effects
				(font
					(size 1 1)
					(thickness 0.15)
				)
			)
		)
		(property "Size" "4.2x4.1"
			(at 0 0 270)
			(unlocked yes)
			(layer "F.Fab")
			(hide yes)
			(effects
				(font
					(size 1 1)
					(thickness 0.15)
				)
			)
		)
		(property "Author" "Antmicro"
			(at 0 0 270)
			(unlocked yes)
			(layer "F.Fab")
			(hide yes)
			(effects
				(font
					(size 1 1)
					(thickness 0.15)
				)
			)
		)
		(property "License" "Apache-2.0"
			(at 0 0 270)
			(unlocked yes)
			(layer "F.Fab")
			(hide yes)
			(effects
				(font
					(size 1 1)
					(thickness 0.15)
				)
			)
		)
		(sheetname "/X710 DCDC converters/")
		(sheetfile "DCDC_converters_X710.kicad_sch")
		(attr smd)
		(fp_line
			(start -0.8 2.05)
			(end 0.8 2.05)
			(stroke
				(width 0.15)
				(type solid)
			)
			(layer "F.SilkS")
		)
		(fp_line
			(start -0.8 -2.05)
			(end 0.8 -2.05)
			(stroke
				(width 0.15)
				(type solid)
			)
			(layer "F.SilkS")
		)
		(fp_rect
			(start -2.85 -2.3)
			(end 2.85 2.3)
			(stroke
				(width 0.05)
				(type solid)
			)
			(fill no)
			(layer "F.CrtYd")
		)
		(fp_rect
			(start -2 -2.05)
			(end 2 2.05)
			(stroke
				(width 0.15)
				(type solid)
			)
			(fill no)
			(layer "F.Fab")
		)
		(fp_text user "${REFERENCE}"
			(at -2.85 5.8 270)
			(layer "F.Fab")
			(effects
				(font
					(size 0.7 0.7)
					(thickness 0.15)
				)
				(justify left bottom)
			)
		)
		(fp_text user "License: Apache-2.0"
			(at -2.85 7 270)
			(layer "F.Fab")
			(effects
				(font
					(size 0.7 0.7)
					(thickness 0.15)
				)
				(justify left bottom)
			)
		)
		(fp_text user "Author: Antmicro"
			(at -2.85 4.6 270)
			(layer "F.Fab")
			(effects
				(font
					(size 0.7 0.7)
					(thickness 0.15)
				)
				(justify left bottom)
			)
		)
		(pad "1" smd rect
			(at 1.85 0 90)
			(size 1.5 3.5)
			(layers "F.Cu" "F.Mask" "F.Paste")
			(net 241 "/X710 DCDC converters/1V88_SW")
			(pintype "passive")
		)
		(pad "2" smd rect
			(at -1.85 0 90)
			(size 1.5 3.5)
			(layers "F.Cu" "F.Mask" "F.Paste")
			(net 338 "/X710 DCDC converters/+1V88_OUT")
			(pintype "passive")
		)
	)
	(footprint "antmicro-footprints:C_0402_1005Metric"
		(layer "F.Cu")
		(at 134.85 129.15 -90)
		(descr "Capacitor SMD 0402")
		(tags "capacitor SMD 0402")
		(property "Reference" "C102"
			(at -0.450004 -7.15 270)
			(layer "F.SilkS")
			(effects
				(font
					(size 0.7 0.7)
					(thickness 0.15)
				)
				(justify left bottom)
			)
		)
		(property "Value" "C_10u_0402"
			(at -1.022927 2.155213 270)
			(layer "F.Fab")
			(effects
				(font
					(size 0.7 0.7)
					(thickness 0.15)
				)
				(justify left bottom)
			)
		)
		(property "Datasheet" "https://www.yageo.com/en/Chart/Download/pdf/CC0402MRX5R5BB106"
			(at 0 0 270)
			(layer "F.Fab")
			(hide yes)
			(effects
				(font
					(size 1.27 1.27)
					(thickness 0.15)
				)
			)
		)
		(property "Description" "SMD Multilayer Ceramic Capacitor, 10 µF, 6.3 V, 0402 [1005 Metric], ± 20%, X5R, CC Series"
			(at 0 0 270)
			(layer "F.Fab")
			(hide yes)
			(effects
				(font
					(size 1.27 1.27)
					(thickness 0.15)
				)
			)
		)
		(property "MPN" "CC0402MRX5R5BB106"
			(at 0 0 270)
			(unlocked yes)
			(layer "F.Fab")
			(hide yes)
			(effects
				(font
					(size 1 1)
					(thickness 0.15)
				)
			)
		)
		(property "Manufacturer" "YAGEO"
			(at 0 0 270)
			(unlocked yes)
			(layer "F.Fab")
			(hide yes)
			(effects
				(font
					(size 1 1)
					(thickness 0.15)
				)
			)
		)
		(property "License" "Apache-2.0"
			(at 0 0 270)
			(unlocked yes)
			(layer "F.Fab")
			(hide yes)
			(effects
				(font
					(size 1 1)
					(thickness 0.15)
				)
			)
		)
		(property "Val" "10u"
			(at 0 0 270)
			(unlocked yes)
			(layer "F.Fab")
			(hide yes)
			(effects
				(font
					(size 1 1)
					(thickness 0.15)
				)
			)
		)
		(property "Voltage" ""
			(at 0 0 270)
			(unlocked yes)
			(layer "F.Fab")
			(hide yes)
			(effects
				(font
					(size 1 1)
					(thickness 0.15)
				)
			)
		)
		(property "Dielectric" ""
			(at 0 0 270)
			(unlocked yes)
			(layer "F.Fab")
			(hide yes)
			(effects
				(font
					(size 1 1)
					(thickness 0.15)
				)
			)
		)
		(property "Author" "Antmicro"
			(at 0 0 270)
			(unlocked yes)
			(layer "F.Fab")
			(hide yes)
			(effects
				(font
					(size 1 1)
					(thickness 0.15)
				)
			)
		)
		(sheetname "/TB Controller - Power/")
		(sheetfile "tb-power.kicad_sch")
		(attr smd)
		(fp_rect
			(start -0.925 -0.47)
			(end 0.925 0.47)
			(stroke
				(width 0.05)
				(type default)
			)
			(fill no)
			(layer "F.CrtYd")
		)
		(fp_line
			(start -0.494 0.248)
			(end -0.494 -0.25)
			(stroke
				(width 0.15)
				(type solid)
			)
			(layer "F.Fab")
		)
		(fp_line
			(start 0.504 0.248)
			(end -0.494 0.248)
			(stroke
				(width 0.15)
				(type solid)
			)
			(layer "F.Fab")
		)
		(fp_line
			(start -0.494 -0.25)
			(end 0.504 -0.25)
			(stroke
				(width 0.15)
				(type solid)
			)
			(layer "F.Fab")
		)
		(fp_line
			(start 0.504 -0.25)
			(end 0.504 0.248)
			(stroke
				(width 0.15)
				(type solid)
			)
			(layer "F.Fab")
		)
		(fp_text user "Author: Antmicro"
			(at -0.939 3.399 270)
			(layer "F.Fab")
			(effects
				(font
					(size 0.7 0.7)
					(thickness 0.15)
				)
				(justify left bottom)
			)
		)
		(fp_text user "License: Apache-2.0"
			(at -0.939 5.799 270)
			(layer "F.Fab")
			(effects
				(font
					(size 0.7 0.7)
					(thickness 0.15)
				)
				(justify left bottom)
			)
		)
		(fp_text user "${REFERENCE}"
			(at -0.939 4.599 270)
			(layer "F.Fab")
			(effects
				(font
					(size 0.7 0.7)
					(thickness 0.15)
				)
				(justify left bottom)
			)
		)
		(pad "1" smd roundrect
			(at -0.48 0 270)
			(size 0.59 0.64)
			(layers "F.Cu" "F.Mask" "F.Paste")
			(roundrect_rratio 0.25)
			(net 23 "GND")
			(pintype "passive")
		)
		(pad "2" smd roundrect
			(at 0.48 0 270)
			(size 0.59 0.64)
			(layers "F.Cu" "F.Mask" "F.Paste")
			(roundrect_rratio 0.25)
			(net 57 "+3V3_TB")
			(pintype "passive")
		)
	)
	(footprint "antmicro-footprints:R_0402_1005Metric"
		(layer "F.Cu")
		(at 117.4 138.72 -90)
		(descr "Resistor SMD 0402")
		(tags "resistor SMD 0402")
		(property "Reference" "R2"
			(at 1.03 -2.6 270)
			(layer "F.SilkS")
			(effects
				(font
					(size 0.7 0.7)
					(thickness 0.15)
				)
				(justify left bottom)
			)
		)
		(property "Value" "R_470R_0402"
			(at -1.011843 1.772047 270)
			(layer "F.Fab")
			(effects
				(font
					(size 0.7 0.7)
					(thickness 0.15)
				)
				(justify left bottom)
			)
		)
		(property "Datasheet" "https://www.bourns.com/docs/product-datasheets/cr.pdf"
			(at 0 0 270)
			(layer "F.Fab")
			(hide yes)
			(effects
				(font
					(size 1.27 1.27)
					(thickness 0.15)
				)
			)
		)
		(property "Description" "SMD Chip Resistor, 470 ohm, ± 1%, 62.5 mW, 0402 [1005 Metric], Thick Film, General Purpose"
			(at 0 0 270)
			(layer "F.Fab")
			(hide yes)
			(effects
				(font
					(size 1.27 1.27)
					(thickness 0.15)
				)
			)
		)
		(property "MPN" "CR0402-FX-4700GLF"
			(at 0 0 270)
			(unlocked yes)
			(layer "F.Fab")
			(hide yes)
			(effects
				(font
					(size 1 1)
					(thickness 0.15)
				)
			)
		)
		(property "Manufacturer" "Bourns"
			(at 0 0 270)
			(unlocked yes)
			(layer "F.Fab")
			(hide yes)
			(effects
				(font
					(size 1 1)
					(thickness 0.15)
				)
			)
		)
		(property "License" "Apache-2.0"
			(at 0 0 270)
			(unlocked yes)
			(layer "F.Fab")
			(hide yes)
			(effects
				(font
					(size 1 1)
					(thickness 0.15)
				)
			)
		)
		(property "Author" "Antmicro"
			(at 0 0 270)
			(unlocked yes)
			(layer "F.Fab")
			(hide yes)
			(effects
				(font
					(size 1 1)
					(thickness 0.15)
				)
			)
		)
		(property "Val" "470R"
			(at 0 0 270)
			(unlocked yes)
			(layer "F.Fab")
			(hide yes)
			(effects
				(font
					(size 1 1)
					(thickness 0.15)
				)
			)
		)
		(property "Tolerance" "1%"
			(at 0 0 270)
			(unlocked yes)
			(layer "F.Fab")
			(hide yes)
			(effects
				(font
					(size 1 1)
					(thickness 0.15)
				)
			)
		)
		(sheetname "/USB-C connector/")
		(sheetfile "USB-C_connector.kicad_sch")
		(attr smd)
		(fp_rect
			(start -0.925 -0.47)
			(end 0.925 0.47)
			(stroke
				(width 0.05)
				(type default)
			)
			(fill no)
			(layer "F.CrtYd")
		)
		(fp_rect
			(start -0.5 -0.25)
			(end 0.5 0.25)
			(stroke
				(width 0.15)
				(type solid)
			)
			(fill no)
			(layer "F.Fab")
		)
		(fp_text user "License: Apache-2.0"
			(at -0.95 5.169 270)
			(layer "F.Fab")
			(effects
				(font
					(size 0.7 0.7)
					(thickness 0.15)
				)
				(justify left bottom)
			)
		)
		(fp_text user "Author: Antmicro"
			(at -0.95 4.169 270)
			(layer "F.Fab")
			(effects
				(font
					(size 0.7 0.7)
					(thickness 0.15)
				)
				(justify left bottom)
			)
		)
		(fp_text user "${REFERENCE}"
			(at -0.95 3.168 270)
			(layer "F.Fab")
			(effects
				(font
					(size 0.7 0.7)
					(thickness 0.15)
				)
				(justify left bottom)
			)
		)
		(pad "1" smd roundrect
			(at -0.48 0 270)
			(size 0.59 0.64)
			(layers "F.Cu" "F.Mask" "F.Paste")
			(roundrect_rratio 0.25)
			(net 164 "Net-(D2-A)")
			(pintype "passive")
		)
		(pad "2" smd roundrect
			(at 0.48 0 270)
			(size 0.59 0.64)
			(layers "F.Cu" "F.Mask" "F.Paste")
			(roundrect_rratio 0.25)
			(net 53 "+5V_USB")
			(pintype "passive")
		)
	)
)
